FILE_TYPE = CONNECTIVITY;
{Allegro Design Entry HDL 16.6-p007 (v16-6-112F) 10/10/2012}
"PAGE_NUMBER" = 106;
0"NC";
1"P3E_CPU0_PE3_OCP_TXN<15:0>";
2"P3E_OCP_CPU0_PE3_C_TXN<15:0>";
3"P3E_CPU0_PE3_OCP_TXP<15:0>";
4"P3E_OCP_CPU0_PE3_C_TXP<15:0>";
5"P3E_OCP_CPU0_PE3_C_TXN<15>";
6"P3E_CPU0_PE3_OCP_TXN<15>";
7"P3E_OCP_CPU0_PE3_C_TXN<14>";
8"P3E_CPU0_PE3_OCP_TXN<14>";
9"P3E_OCP_CPU0_PE3_C_TXN<13>";
10"P3E_OCP_CPU0_PE3_C_TXN<11>";
11"P3E_CPU0_PE3_OCP_TXN<13>";
12"P3E_CPU0_PE3_OCP_TXN<11>";
13"P3E_OCP_CPU0_PE3_C_TXN<12>";
14"P3E_CPU0_PE3_OCP_TXN<12>";
15"P3E_OCP_CPU0_PE3_C_TXP<15>";
16"P3E_OCP_CPU0_PE3_C_TXP<13>";
17"P3E_OCP_CPU0_PE3_C_TXP<14>";
18"P3E_CPU0_PE3_OCP_TXP<13>";
19"P3E_CPU0_PE3_OCP_TXP<15>";
20"P3E_CPU0_PE3_OCP_TXP<14>";
21"P3E_OCP_CPU0_PE3_C_TXP<12>";
22"P3E_OCP_CPU0_PE3_C_TXP<11>";
23"P3E_CPU0_PE3_OCP_TXP<11>";
24"P3E_CPU0_PE3_OCP_TXP<12>";
25"P3E_OCP_CPU0_PE3_C_TXN<9>";
26"P3E_OCP_CPU0_PE3_C_TXN<8>";
27"P3E_OCP_CPU0_PE3_C_TXN<10>";
28"P3E_CPU0_PE3_OCP_TXN<9>";
29"P3E_CPU0_PE3_OCP_TXN<10>";
30"P3E_CPU0_PE3_OCP_TXN<8>";
31"P3E_OCP_CPU0_PE3_C_TXN<7>";
32"P3E_CPU0_PE3_OCP_TXN<7>";
33"P3E_OCP_CPU0_PE3_C_TXN<6>";
34"P3E_CPU0_PE3_OCP_TXN<6>";
35"P3E_OCP_CPU0_PE3_C_TXN<5>";
36"P3E_OCP_CPU0_PE3_C_TXN<3>";
37"P3E_OCP_CPU0_PE3_C_TXN<4>";
38"P3E_CPU0_PE3_OCP_TXN<5>";
39"P3E_CPU0_PE3_OCP_TXN<3>";
40"P3E_CPU0_PE3_OCP_TXN<4>";
41"P3E_OCP_CPU0_PE3_C_TXN<1>";
42"P3E_CPU0_PE3_OCP_TXN<1>";
43"P3E_OCP_CPU0_PE3_C_TXN<2>";
44"P3E_CPU0_PE3_OCP_TXN<2>";
45"P3E_OCP_CPU0_PE3_C_TXP<9>";
46"P3E_OCP_CPU0_PE3_C_TXP<10>";
47"P3E_OCP_CPU0_PE3_C_TXP<8>";
48"P3E_CPU0_PE3_OCP_TXP<9>";
49"P3E_CPU0_PE3_OCP_TXP<10>";
50"P3E_CPU0_PE3_OCP_TXP<8>";
51"P3E_OCP_CPU0_PE3_C_TXP<7>";
52"P3E_OCP_CPU0_PE3_C_TXP<6>";
53"P3E_CPU0_PE3_OCP_TXP<7>";
54"P3E_CPU0_PE3_OCP_TXP<6>";
55"P3E_OCP_CPU0_PE3_C_TXP<5>";
56"P3E_OCP_CPU0_PE3_C_TXP<4>";
57"P3E_OCP_CPU0_PE3_C_TXP<3>";
58"P3E_CPU0_PE3_OCP_TXP<5>";
59"P3E_CPU0_PE3_OCP_TXP<3>";
60"P3E_CPU0_PE3_OCP_TXP<4>";
61"P3E_OCP_CPU0_PE3_C_TXP<2>";
62"P3E_OCP_CPU0_PE3_C_TXP<1>";
63"P3E_OCP_CPU0_PE3_C_TXP<0>";
64"P3E_CPU0_PE3_OCP_TXP<1>";
65"P3E_CPU0_PE3_OCP_TXP<2>";
66"P3E_CPU0_PE3_OCP_TXP<0>";
67"P3E_OCP_CPU0_PE3_C_TXN<0>";
68"P3E_CPU0_PE3_OCP_TXN<0>";
%"CAP"
"1","(-4100,2650)","2","mstr_discrete","I10";
;
LOCATION"C1R2"
VALUE"0.22UF"
PACK_TYPE"0402"
VOLTAGE"16V"
MATERIAL"X7R"
PART_NUMBER"A36096-155"
TOLERANCE"10%"
BOM_COST"IO_SLOT"
CDS_LIB"mstr_discrete"
CDS_SEC"1"
$SEC"1"
CDS_LOCATION"C1R2"
ROOM"PCIE_STEERING";
"A"
$PN"1"66;
"B"
$PN"2"63;
%"CAP"
"1","(-6500,2650)","2","mstr_discrete","I100";
;
LOCATION"C1M12"
PART_NUMBER"A36096-155"
VALUE"0.22UF"
TOLERANCE"10%"
PACK_TYPE"0402"
VOLTAGE"16V"
MATERIAL"X7R"
CDS_LIB"mstr_discrete"
BOM_COST"IO_SLOT"
CDS_SEC"1"
$SEC"1"
CDS_LOCATION"C1M12"
ROOM"PCIE_STEERING";
"A"
$PN"1"24;
"B"
$PN"2"21;
%"TAP"
"7","(-6500,2100)","0","mstr_standard","I101";
;
CDS_LIB"mstr_standard"
BODY_TYPE"PLUMBING"
HDL_TAP"TRUE";
"B \NAC \NWC"4;
"S \NAC"
BN"12"21;
%"CAP"
"1","(-6700,2350)","2","mstr_discrete","I102";
;
LOCATION"C1M10"
PART_NUMBER"A36096-155"
VALUE"0.22UF"
TOLERANCE"10%"
PACK_TYPE"0402"
VOLTAGE"16V"
MATERIAL"X7R"
CDS_LIB"mstr_discrete"
BOM_COST"IO_SLOT"
CDS_SEC"1"
$SEC"1"
CDS_LOCATION"C1M10"
ROOM"PCIE_STEERING";
"A"
$PN"1"18;
"B"
$PN"2"16;
%"TAP"
"7","(-6700,2100)","0","mstr_standard","I103";
;
CDS_LIB"mstr_standard"
BODY_TYPE"PLUMBING"
HDL_TAP"TRUE";
"B \NAC \NWC"4;
"S \NAC"
BN"13"16;
%"TAP"
"7","(-6900,2100)","0","mstr_standard","I104";
;
CDS_LIB"mstr_standard"
BODY_TYPE"PLUMBING"
HDL_TAP"TRUE";
"B \NAC \NWC"4;
"S \NAC"
BN"14"17;
%"CAP"
"1","(-6900,2650)","2","mstr_discrete","I105";
;
LOCATION"C1M8"
PART_NUMBER"A36096-155"
VALUE"0.22UF"
TOLERANCE"10%"
PACK_TYPE"0402"
VOLTAGE"16V"
MATERIAL"X7R"
CDS_LIB"mstr_discrete"
CDS_SEC"1"
$SEC"1"
CDS_LOCATION"C1M8"
ROOM"PCIE_STEERING";
"A"
$PN"1"20;
"B"
$PN"2"17;
%"TAP"
"3","(-7100,2900)","0","mstr_standard","I106";
;
CDS_LIB"mstr_standard"
BODY_TYPE"PLUMBING"
HDL_TAP"TRUE";
"B \NAC \NWC"3;
"S \NAC"
BN"15"19;
%"TAP"
"7","(-7100,2100)","0","mstr_standard","I108";
;
CDS_LIB"mstr_standard"
BODY_TYPE"PLUMBING"
HDL_TAP"TRUE";
"B \NAC \NWC"4;
"S \NAC"
BN"15"15;
%"CAP"
"1","(-7100,2350)","2","mstr_discrete","I109";
;
LOCATION"C1M6"
PART_NUMBER"A36096-155"
VALUE"0.22UF"
TOLERANCE"10%"
PACK_TYPE"0402"
VOLTAGE"16V"
MATERIAL"X7R"
CDS_LIB"mstr_discrete"
CDS_SEC"1"
$SEC"1"
CDS_LOCATION"C1M6"
ROOM"PCIE_STEERING";
"A"
$PN"1"19;
"B"
$PN"2"15;
%"TAP"
"3","(-4300,2900)","0","mstr_standard","I11";
;
CDS_LIB"mstr_standard"
BODY_TYPE"PLUMBING"
HDL_TAP"TRUE";
"B \NAC \NWC"3;
"S \NAC"
BN"1"64;
%"TAP"
"3","(-6450,1900)","0","mstr_standard","I110";
;
CDS_LIB"mstr_standard"
BODY_TYPE"PLUMBING"
HDL_TAP"TRUE";
"B \NAC \NWC"1;
"S \NAC"
BN"12"14;
%"CAP"
"1","(-6450,1650)","2","mstr_discrete","I111";
;
LOCATION"C1M13"
PART_NUMBER"A36096-155"
VALUE"0.22UF"
TOLERANCE"10%"
PACK_TYPE"0402"
VOLTAGE"16V"
MATERIAL"X7R"
CDS_LIB"mstr_discrete"
BOM_COST"IO_SLOT"
CDS_SEC"1"
$SEC"1"
CDS_LOCATION"C1M13"
ROOM"PCIE_STEERING";
"A"
$PN"1"14;
"B"
$PN"2"13;
%"TAP"
"3","(-6650,1900)","0","mstr_standard","I112";
;
CDS_LIB"mstr_standard"
BODY_TYPE"PLUMBING"
HDL_TAP"TRUE";
"B \NAC \NWC"1;
"S \NAC"
BN"13"11;
%"TAP"
"3","(-6850,1900)","0","mstr_standard","I113";
;
CDS_LIB"mstr_standard"
BODY_TYPE"PLUMBING"
HDL_TAP"TRUE";
"B \NAC \NWC"1;
"S \NAC"
BN"14"8;
%"CAP"
"1","(-6850,1650)","2","mstr_discrete","I114";
;
LOCATION"C1M9"
PART_NUMBER"A36096-155"
VALUE"0.22UF"
TOLERANCE"10%"
PACK_TYPE"0402"
VOLTAGE"16V"
MATERIAL"X7R"
CDS_LIB"mstr_discrete"
CDS_SEC"1"
$SEC"1"
CDS_LOCATION"C1M9"
ROOM"PCIE_STEERING";
"A"
$PN"1"8;
"B"
$PN"2"7;
%"TAP"
"7","(-6450,1100)","0","mstr_standard","I115";
;
CDS_LIB"mstr_standard"
BODY_TYPE"PLUMBING"
HDL_TAP"TRUE";
"B \NAC \NWC"2;
"S \NAC"
BN"12"13;
%"TAP"
"7","(-6650,1100)","0","mstr_standard","I116";
;
CDS_LIB"mstr_standard"
BODY_TYPE"PLUMBING"
HDL_TAP"TRUE";
"B \NAC \NWC"2;
"S \NAC"
BN"13"9;
%"CAP"
"1","(-6650,1350)","2","mstr_discrete","I117";
;
LOCATION"C1M11"
PART_NUMBER"A36096-155"
VALUE"0.22UF"
TOLERANCE"10%"
PACK_TYPE"0402"
VOLTAGE"16V"
MATERIAL"X7R"
CDS_LIB"mstr_discrete"
BOM_COST"IO_SLOT"
CDS_SEC"1"
$SEC"1"
CDS_LOCATION"C1M11"
ROOM"PCIE_STEERING";
"A"
$PN"1"11;
"B"
$PN"2"9;
%"TAP"
"7","(-6850,1100)","0","mstr_standard","I118";
;
CDS_LIB"mstr_standard"
BODY_TYPE"PLUMBING"
HDL_TAP"TRUE";
"B \NAC \NWC"2;
"S \NAC"
BN"14"7;
%"TAP"
"3","(-7050,1900)","0","mstr_standard","I119";
;
CDS_LIB"mstr_standard"
BODY_TYPE"PLUMBING"
HDL_TAP"TRUE";
"B \NAC \NWC"1;
"S \NAC"
BN"15"6;
%"TAP"
"7","(-7050,1100)","0","mstr_standard","I121";
;
CDS_LIB"mstr_standard"
BODY_TYPE"PLUMBING"
HDL_TAP"TRUE";
"B \NAC \NWC"2;
"S \NAC"
BN"15"5;
%"CAP"
"1","(-7050,1350)","2","mstr_discrete","I122";
;
LOCATION"C1M7"
PART_NUMBER"A36096-155"
VALUE"0.22UF"
TOLERANCE"10%"
PACK_TYPE"0402"
VOLTAGE"16V"
MATERIAL"X7R"
CDS_LIB"mstr_discrete"
CDS_SEC"1"
$SEC"1"
CDS_LOCATION"C1M7"
ROOM"PCIE_STEERING";
"A"
$PN"1"6;
"B"
$PN"2"5;
%"CAP"
"1","(-5275,1650)","2","mstr_discrete","I123";
;
LOCATION"C2R7"
PART_NUMBER"A36096-155"
VALUE"0.22UF"
TOLERANCE"10%"
PACK_TYPE"0402"
VOLTAGE"16V"
MATERIAL"X7R"
CDS_LIB"mstr_discrete"
BOM_COST"IO_SLOT"
CDS_SEC"1"
$SEC"1"
CDS_LOCATION"C2R7"
ROOM"PCIE_STEERING";
"A"
$PN"1"34;
"B"
$PN"2"33;
%"TAP"
"7","(-5300,2100)","0","mstr_standard","I124";
;
CDS_LIB"mstr_standard"
BODY_TYPE"PLUMBING"
HDL_TAP"TRUE";
"B \NAC \NWC"4;
"S \NAC"
BN"6"52;
%"TAP"
"3","(-5500,2900)","0","mstr_standard","I125";
;
CDS_LIB"mstr_standard"
BODY_TYPE"PLUMBING"
HDL_TAP"TRUE";
"B \NAC \NWC"3;
"S \NAC"
BN"7"53;
%"TAP"
"3","(-4900,2900)","0","mstr_standard","I126";
;
CDS_LIB"mstr_standard"
BODY_TYPE"PLUMBING"
HDL_TAP"TRUE";
"B \NAC \NWC"3;
"S \NAC"
BN"4"60;
%"TAP"
"3","(-5100,2900)","0","mstr_standard","I127";
;
CDS_LIB"mstr_standard"
BODY_TYPE"PLUMBING"
HDL_TAP"TRUE";
"B \NAC \NWC"3;
"S \NAC"
BN"5"58;
%"CAP"
"1","(-4900,2650)","2","mstr_discrete","I128";
;
LOCATION"C1R10"
PART_NUMBER"A36096-155"
VALUE"0.22UF"
TOLERANCE"10%"
PACK_TYPE"0402"
VOLTAGE"16V"
MATERIAL"X7R"
CDS_LIB"mstr_discrete"
BOM_COST"IO_SLOT"
CDS_SEC"1"
$SEC"1"
CDS_LOCATION"C1R10"
ROOM"PCIE_STEERING";
"A"
$PN"1"60;
"B"
$PN"2"56;
%"TAP"
"7","(-4900,2100)","0","mstr_standard","I129";
;
CDS_LIB"mstr_standard"
BODY_TYPE"PLUMBING"
HDL_TAP"TRUE";
"B \NAC \NWC"4;
"S \NAC"
BN"4"56;
%"CAP"
"1","(-5100,2350)","2","mstr_discrete","I130";
;
CDS_LOCATION"C2R14"
LOCATION"C2R14"
PART_NUMBER"A36096-155"
VALUE"0.22UF"
TOLERANCE"10%"
PACK_TYPE"0402"
VOLTAGE"16V"
MATERIAL"X7R"
CDS_LIB"mstr_discrete"
BOM_COST"IO_SLOT"
CDS_SEC"1"
$SEC"1"
ROOM"PCIE_STEERING";
"A"
$PN"1"58;
"B"
$PN"2"55;
%"TAP"
"7","(-5100,2100)","0","mstr_standard","I131";
;
CDS_LIB"mstr_standard"
BODY_TYPE"PLUMBING"
HDL_TAP"TRUE";
"B \NAC \NWC"4;
"S \NAC"
BN"5"55;
%"TAP"
"3","(-4875,1900)","0","mstr_standard","I133";
;
CDS_LIB"mstr_standard"
BODY_TYPE"PLUMBING"
HDL_TAP"TRUE";
"B \NAC \NWC"1;
"S \NAC"
BN"4"40;
%"CAP"
"1","(-4875,1650)","2","mstr_discrete","I134";
;
PART_NUMBER"A36096-155"
VALUE"0.22UF"
TOLERANCE"10%"
PACK_TYPE"0402"
VOLTAGE"16V"
MATERIAL"X7R"
LOCATION"C1R9"
CDS_LIB"mstr_discrete"
BOM_COST"IO_SLOT"
CDS_SEC"1"
$SEC"1"
CDS_LOCATION"C1R9"
ROOM"PCIE_STEERING";
"A"
$PN"1"40;
"B"
$PN"2"37;
%"TAP"
"3","(-5075,1900)","0","mstr_standard","I135";
;
CDS_LIB"mstr_standard"
BODY_TYPE"PLUMBING"
HDL_TAP"TRUE";
"B \NAC \NWC"1;
"S \NAC"
BN"5"38;
%"TAP"
"7","(-4875,1100)","0","mstr_standard","I136";
;
CDS_LIB"mstr_standard"
BODY_TYPE"PLUMBING"
HDL_TAP"TRUE";
"B \NAC \NWC"2;
"S \NAC"
BN"4"37;
%"CAP"
"1","(-5075,1350)","2","mstr_discrete","I137";
;
CDS_LOCATION"C2R13"
LOCATION"C2R13"
PART_NUMBER"A36096-155"
VALUE"0.22UF"
TOLERANCE"10%"
PACK_TYPE"0402"
VOLTAGE"16V"
MATERIAL"X7R"
CDS_LIB"mstr_discrete"
BOM_COST"IO_SLOT"
CDS_SEC"1"
$SEC"1"
ROOM"PCIE_STEERING";
"A"
$PN"1"38;
"B"
$PN"2"35;
%"TAP"
"7","(-5075,1100)","0","mstr_standard","I138";
;
CDS_LIB"mstr_standard"
BODY_TYPE"PLUMBING"
HDL_TAP"TRUE";
"B \NAC \NWC"2;
"S \NAC"
BN"5"35;
%"TAP"
"3","(-5300,2900)","0","mstr_standard","I140";
;
CDS_LIB"mstr_standard"
BODY_TYPE"PLUMBING"
HDL_TAP"TRUE";
"B \NAC \NWC"3;
"S \NAC"
BN"6"54;
%"CAP"
"1","(-5300,2650)","2","mstr_discrete","I141";
;
LOCATION"C2R8"
PART_NUMBER"A36096-155"
VALUE"0.22UF"
TOLERANCE"10%"
PACK_TYPE"0402"
VOLTAGE"16V"
MATERIAL"X7R"
CDS_LIB"mstr_discrete"
BOM_COST"IO_SLOT"
CDS_SEC"1"
$SEC"1"
CDS_LOCATION"C2R8"
ROOM"PCIE_STEERING";
"A"
$PN"1"54;
"B"
$PN"2"52;
%"CAP"
"1","(-5500,2350)","2","mstr_discrete","I142";
;
LOCATION"C2R10"
PART_NUMBER"A36096-155"
VALUE"0.22UF"
TOLERANCE"10%"
VOLTAGE"16V"
MATERIAL"X7R"
PACK_TYPE"0402"
CDS_LIB"mstr_discrete"
BOM_COST"IO_SLOT"
CDS_SEC"1"
$SEC"1"
CDS_LOCATION"C2R10"
ROOM"PCIE_STEERING";
"A"
$PN"1"53;
"B"
$PN"2"51;
%"TAP"
"7","(-5500,2100)","0","mstr_standard","I143";
;
CDS_LIB"mstr_standard"
BODY_TYPE"PLUMBING"
HDL_TAP"TRUE";
"B \NAC \NWC"4;
"S \NAC"
BN"7"51;
%"TAP"
"3","(-5275,1900)","0","mstr_standard","I144";
;
CDS_LIB"mstr_standard"
BODY_TYPE"PLUMBING"
HDL_TAP"TRUE";
"B \NAC \NWC"1;
"S \NAC"
BN"6"34;
%"TAP"
"3","(-5475,1900)","0","mstr_standard","I145";
;
CDS_LIB"mstr_standard"
BODY_TYPE"PLUMBING"
HDL_TAP"TRUE";
"B \NAC \NWC"1;
"S \NAC"
BN"7"32;
%"TAP"
"7","(-5275,1100)","0","mstr_standard","I146";
;
CDS_LIB"mstr_standard"
BODY_TYPE"PLUMBING"
HDL_TAP"TRUE";
"B \NAC \NWC"2;
"S \NAC"
BN"6"33;
%"CAP"
"1","(-5475,1350)","2","mstr_discrete","I147";
;
LOCATION"C2R9"
PART_NUMBER"A36096-155"
VALUE"0.22UF"
TOLERANCE"10%"
PACK_TYPE"0402"
VOLTAGE"16V"
MATERIAL"X7R"
CDS_LIB"mstr_discrete"
BOM_COST"IO_SLOT"
CDS_SEC"1"
$SEC"1"
CDS_LOCATION"C2R9"
ROOM"PCIE_STEERING";
"A"
$PN"1"32;
"B"
$PN"2"31;
%"TAP"
"7","(-5475,1100)","0","mstr_standard","I148";
;
CDS_LIB"mstr_standard"
BODY_TYPE"PLUMBING"
HDL_TAP"TRUE";
"B \NAC \NWC"2;
"S \NAC"
BN"7"31;
%"TAP"
"7","(-4100,2100)","0","mstr_standard","I25";
;
CDS_LIB"mstr_standard"
BODY_TYPE"PLUMBING"
HDL_TAP"TRUE";
"B \NAC \NWC"4;
"S \NAC"
BN"0"63;
%"CAP"
"1","(-4300,2350)","2","mstr_discrete","I26";
;
LOCATION"C1R4"
PART_NUMBER"A36096-155"
VALUE"0.22UF"
TOLERANCE"10%"
PACK_TYPE"0402"
VOLTAGE"16V"
MATERIAL"X7R"
BOM_COST"IO_SLOT"
CDS_LIB"mstr_discrete"
CDS_SEC"1"
$SEC"1"
CDS_LOCATION"C1R4"
ROOM"PCIE_STEERING";
"A"
$PN"1"64;
"B"
$PN"2"62;
%"TAP"
"7","(-4300,2100)","0","mstr_standard","I27";
;
CDS_LIB"mstr_standard"
BODY_TYPE"PLUMBING"
HDL_TAP"TRUE";
"B \NAC \NWC"4;
"S \NAC"
BN"1"62;
%"TAP"
"3","(-4075,1900)","0","mstr_standard","I28";
;
CDS_LIB"mstr_standard"
BODY_TYPE"PLUMBING"
HDL_TAP"TRUE";
"B \NAC \NWC"1;
"S \NAC"
BN"0"68;
%"CAP"
"1","(-4075,1650)","2","mstr_discrete","I29";
;
LOCATION"C1R1"
PART_NUMBER"A36096-155"
VALUE"0.22UF"
TOLERANCE"10%"
PACK_TYPE"0402"
VOLTAGE"16V"
MATERIAL"X7R"
BOM_COST"IO_SLOT"
CDS_LIB"mstr_discrete"
CDS_SEC"1"
$SEC"1"
CDS_LOCATION"C1R1"
ROOM"PCIE_STEERING";
"A"
$PN"1"68;
"B"
$PN"2"67;
%"TAP"
"3","(-4275,1900)","0","mstr_standard","I30";
;
CDS_LIB"mstr_standard"
BODY_TYPE"PLUMBING"
HDL_TAP"TRUE";
"B \NAC \NWC"1;
"S \NAC"
BN"1"42;
%"TAP"
"7","(-4075,1100)","0","mstr_standard","I36";
;
CDS_LIB"mstr_standard"
BODY_TYPE"PLUMBING"
HDL_TAP"TRUE";
"B \NAC \NWC"2;
"S \NAC"
BN"0"67;
%"CAP"
"1","(-4275,1350)","2","mstr_discrete","I37";
;
LOCATION"C1R3"
PART_NUMBER"A36096-155"
VALUE"0.22UF"
TOLERANCE"10%"
PACK_TYPE"0402"
VOLTAGE"16V"
MATERIAL"X7R"
BOM_COST"IO_SLOT"
CDS_LIB"mstr_discrete"
CDS_SEC"1"
$SEC"1"
CDS_LOCATION"C1R3"
ROOM"PCIE_STEERING";
"A"
$PN"1"42;
"B"
$PN"2"41;
%"TAP"
"7","(-4275,1100)","0","mstr_standard","I38";
;
CDS_LIB"mstr_standard"
BODY_TYPE"PLUMBING"
HDL_TAP"TRUE";
"B \NAC \NWC"2;
"S \NAC"
BN"1"41;
%"TAP"
"3","(-4500,2900)","0","mstr_standard","I39";
;
CDS_LIB"mstr_standard"
BODY_TYPE"PLUMBING"
HDL_TAP"TRUE";
"B \NAC \NWC"3;
"S \NAC"
BN"2"65;
%"CAP"
"1","(-4500,2650)","2","mstr_discrete","I40";
;
LOCATION"C1R6"
PART_NUMBER"A36096-155"
VALUE"0.22UF"
TOLERANCE"10%"
PACK_TYPE"0402"
VOLTAGE"16V"
MATERIAL"X7R"
CDS_LIB"mstr_discrete"
CDS_SEC"1"
$SEC"1"
CDS_LOCATION"C1R6"
ROOM"PCIE_STEERING";
"A"
$PN"1"65;
"B"
$PN"2"61;
%"TAP"
"3","(-4700,2900)","0","mstr_standard","I41";
;
CDS_LIB"mstr_standard"
BODY_TYPE"PLUMBING"
HDL_TAP"TRUE";
"B \NAC \NWC"3;
"S \NAC"
BN"3"59;
%"TAP"
"7","(-4500,2100)","0","mstr_standard","I54";
;
CDS_LIB"mstr_standard"
BODY_TYPE"PLUMBING"
HDL_TAP"TRUE";
"B \NAC \NWC"4;
"S \NAC"
BN"2"61;
%"CAP"
"1","(-4700,2350)","2","mstr_discrete","I55";
;
LOCATION"C1R8"
PART_NUMBER"A36096-155"
VALUE"0.22UF"
TOLERANCE"10%"
PACK_TYPE"0402"
VOLTAGE"16V"
MATERIAL"X7R"
CDS_LIB"mstr_discrete"
CDS_SEC"1"
$SEC"1"
CDS_LOCATION"C1R8"
ROOM"PCIE_STEERING";
"A"
$PN"1"59;
"B"
$PN"2"57;
%"TAP"
"7","(-4700,2100)","0","mstr_standard","I56";
;
CDS_LIB"mstr_standard"
BODY_TYPE"PLUMBING"
HDL_TAP"TRUE";
"B \NAC \NWC"4;
"S \NAC"
BN"3"57;
%"TAP"
"3","(-4475,1900)","0","mstr_standard","I58";
;
CDS_LIB"mstr_standard"
BODY_TYPE"PLUMBING"
HDL_TAP"TRUE";
"B \NAC \NWC"1;
"S \NAC"
BN"2"44;
%"CAP"
"1","(-4475,1650)","2","mstr_discrete","I59";
;
LOCATION"C1R5"
PART_NUMBER"A36096-155"
VALUE"0.22UF"
TOLERANCE"10%"
PACK_TYPE"0402"
VOLTAGE"16V"
MATERIAL"X7R"
BOM_COST"IO_SLOT"
CDS_LIB"mstr_discrete"
CDS_SEC"1"
$SEC"1"
CDS_LOCATION"C1R5"
ROOM"PCIE_STEERING";
"A"
$PN"1"44;
"B"
$PN"2"43;
%"TAP"
"3","(-4675,1900)","0","mstr_standard","I60";
;
CDS_LIB"mstr_standard"
BODY_TYPE"PLUMBING"
HDL_TAP"TRUE";
"B \NAC \NWC"1;
"S \NAC"
BN"3"39;
%"TAP"
"7","(-4475,1100)","0","mstr_standard","I69";
;
CDS_LIB"mstr_standard"
BODY_TYPE"PLUMBING"
HDL_TAP"TRUE";
"B \NAC \NWC"2;
"S \NAC"
BN"2"43;
%"CAP"
"1","(-4675,1350)","2","mstr_discrete","I70";
;
LOCATION"C1R7"
PART_NUMBER"A36096-155"
VALUE"0.22UF"
TOLERANCE"10%"
PACK_TYPE"0402"
VOLTAGE"16V"
MATERIAL"X7R"
BOM_COST"IO_SLOT"
CDS_LIB"mstr_discrete"
CDS_SEC"1"
$SEC"1"
CDS_LOCATION"C1R7"
ROOM"PCIE_STEERING";
"A"
$PN"1"39;
"B"
$PN"2"36;
%"TAP"
"7","(-4675,1100)","0","mstr_standard","I72";
;
CDS_LIB"mstr_standard"
BODY_TYPE"PLUMBING"
HDL_TAP"TRUE";
"B \NAC \NWC"2;
"S \NAC"
BN"3"36;
%"TAP"
"7","(-5900,2100)","0","mstr_standard","I73";
;
CDS_LIB"mstr_standard"
BODY_TYPE"PLUMBING"
HDL_TAP"TRUE";
"B \NAC \NWC"4;
"S \NAC"
BN"9"45;
%"TAP"
"7","(-5650,1100)","0","mstr_standard","I74";
;
CDS_LIB"mstr_standard"
BODY_TYPE"PLUMBING"
HDL_TAP"TRUE";
"B \NAC \NWC"2;
"S \NAC"
BN"8"26;
%"TAP"
"3","(-5700,2900)","0","mstr_standard","I75";
;
CDS_LIB"mstr_standard"
BODY_TYPE"PLUMBING"
HDL_TAP"TRUE";
"B \NAC \NWC"3;
"S \NAC"
BN"8"50;
%"CAP"
"1","(-5700,2650)","2","mstr_discrete","I76";
;
LOCATION"C2M14"
PART_NUMBER"A36096-155"
VALUE"0.22UF"
TOLERANCE"10%"
PACK_TYPE"0402"
VOLTAGE"16V"
MATERIAL"X7R"
CDS_LIB"mstr_discrete"
BOM_COST"IO_SLOT"
CDS_SEC"1"
$SEC"1"
CDS_LOCATION"C2M14"
ROOM"PCIE_STEERING";
"A"
$PN"1"50;
"B"
$PN"2"47;
%"TAP"
"7","(-5700,2100)","0","mstr_standard","I77";
;
CDS_LIB"mstr_standard"
BODY_TYPE"PLUMBING"
HDL_TAP"TRUE";
"B \NAC \NWC"4;
"S \NAC"
BN"8"47;
%"CAP"
"1","(-5900,2350)","2","mstr_discrete","I78";
;
LOCATION"C1M18"
PART_NUMBER"A36096-155"
VALUE"0.22UF"
TOLERANCE"10%"
VOLTAGE"16V"
MATERIAL"X7R"
PACK_TYPE"0402"
CDS_LIB"mstr_discrete"
BOM_COST"IO_SLOT"
CDS_SEC"1"
$SEC"1"
CDS_LOCATION"C1M18"
ROOM"PCIE_STEERING";
"A"
$PN"1"48;
"B"
$PN"2"45;
%"TAP"
"3","(-5900,2900)","0","mstr_standard","I79";
;
CDS_LIB"mstr_standard"
BODY_TYPE"PLUMBING"
HDL_TAP"TRUE";
"B \NAC \NWC"3;
"S \NAC"
BN"9"48;
%"TAP"
"3","(-6100,2900)","0","mstr_standard","I80";
;
CDS_LIB"mstr_standard"
BODY_TYPE"PLUMBING"
HDL_TAP"TRUE";
"B \NAC \NWC"3;
"S \NAC"
BN"10"49;
%"TAP"
"3","(-6300,2900)","0","mstr_standard","I81";
;
CDS_LIB"mstr_standard"
BODY_TYPE"PLUMBING"
HDL_TAP"TRUE";
"B \NAC \NWC"3;
"S \NAC"
BN"11"23;
%"CAP"
"1","(-6100,2650)","2","mstr_discrete","I82";
;
LOCATION"C1M16"
PART_NUMBER"A36096-155"
VALUE"0.22UF"
TOLERANCE"10%"
PACK_TYPE"0402"
VOLTAGE"16V"
MATERIAL"X7R"
CDS_LIB"mstr_discrete"
BOM_COST"IO_SLOT"
CDS_SEC"1"
$SEC"1"
CDS_LOCATION"C1M16"
ROOM"PCIE_STEERING";
"A"
$PN"1"49;
"B"
$PN"2"46;
%"TAP"
"7","(-6100,2100)","0","mstr_standard","I83";
;
CDS_LIB"mstr_standard"
BODY_TYPE"PLUMBING"
HDL_TAP"TRUE";
"B \NAC \NWC"4;
"S \NAC"
BN"10"46;
%"TAP"
"7","(-6300,2100)","0","mstr_standard","I84";
;
CDS_LIB"mstr_standard"
BODY_TYPE"PLUMBING"
HDL_TAP"TRUE";
"B \NAC \NWC"4;
"S \NAC"
BN"11"22;
%"CAP"
"1","(-6300,2350)","2","mstr_discrete","I85";
;
LOCATION"C1M14"
PART_NUMBER"A36096-155"
VALUE"0.22UF"
PACK_TYPE"0402"
MATERIAL"X7R"
VOLTAGE"16V"
TOLERANCE"10%"
CDS_LIB"mstr_discrete"
BOM_COST"IO_SLOT"
CDS_SEC"1"
$SEC"1"
CDS_LOCATION"C1M14"
ROOM"PCIE_STEERING";
"A"
$PN"1"23;
"B"
$PN"2"22;
%"CAP"
"1","(-5650,1650)","2","mstr_discrete","I86";
;
LOCATION"C2M15"
PART_NUMBER"A36096-155"
VALUE"0.22UF"
TOLERANCE"10%"
PACK_TYPE"0402"
VOLTAGE"16V"
MATERIAL"X7R"
CDS_LIB"mstr_discrete"
BOM_COST"IO_SLOT"
CDS_SEC"1"
$SEC"1"
CDS_LOCATION"C2M15"
ROOM"PCIE_STEERING";
"A"
$PN"1"30;
"B"
$PN"2"26;
%"TAP"
"3","(-5650,1900)","0","mstr_standard","I87";
;
CDS_LIB"mstr_standard"
BODY_TYPE"PLUMBING"
HDL_TAP"TRUE";
"B \NAC \NWC"1;
"S \NAC"
BN"8"30;
%"TAP"
"3","(-5850,1900)","0","mstr_standard","I88";
;
CDS_LIB"mstr_standard"
BODY_TYPE"PLUMBING"
HDL_TAP"TRUE";
"B \NAC \NWC"1;
"S \NAC"
BN"9"28;
%"TAP"
"7","(-5850,1100)","0","mstr_standard","I89";
;
CDS_LIB"mstr_standard"
BODY_TYPE"PLUMBING"
HDL_TAP"TRUE";
"B \NAC \NWC"2;
"S \NAC"
BN"9"25;
%"TAP"
"3","(-4100,2900)","0","mstr_standard","I9";
;
CDS_LIB"mstr_standard"
BODY_TYPE"PLUMBING"
HDL_TAP"TRUE";
"B \NAC \NWC"3;
"S \NAC"
BN"0"66;
%"CAP"
"1","(-5850,1350)","2","mstr_discrete","I90";
;
LOCATION"C1M19"
PART_NUMBER"A36096-155"
VALUE"0.22UF"
TOLERANCE"10%"
PACK_TYPE"0402"
VOLTAGE"16V"
MATERIAL"X7R"
CDS_LIB"mstr_discrete"
BOM_COST"IO_SLOT"
CDS_SEC"1"
$SEC"1"
CDS_LOCATION"C1M19"
ROOM"PCIE_STEERING";
"A"
$PN"1"28;
"B"
$PN"2"25;
%"TAP"
"3","(-6050,1900)","0","mstr_standard","I91";
;
CDS_LIB"mstr_standard"
BODY_TYPE"PLUMBING"
HDL_TAP"TRUE";
"B \NAC \NWC"1;
"S \NAC"
BN"10"29;
%"CAP"
"1","(-6050,1650)","2","mstr_discrete","I92";
;
LOCATION"C1M17"
PART_NUMBER"A36096-155"
VALUE"0.22UF"
TOLERANCE"10%"
PACK_TYPE"0402"
VOLTAGE"16V"
MATERIAL"X7R"
CDS_LIB"mstr_discrete"
BOM_COST"IO_SLOT"
CDS_SEC"1"
$SEC"1"
CDS_LOCATION"C1M17"
ROOM"PCIE_STEERING";
"A"
$PN"1"29;
"B"
$PN"2"27;
%"TAP"
"3","(-6250,1900)","0","mstr_standard","I93";
;
CDS_LIB"mstr_standard"
BODY_TYPE"PLUMBING"
HDL_TAP"TRUE";
"B \NAC \NWC"1;
"S \NAC"
BN"11"12;
%"TAP"
"7","(-6050,1100)","0","mstr_standard","I94";
;
CDS_LIB"mstr_standard"
BODY_TYPE"PLUMBING"
HDL_TAP"TRUE";
"B \NAC \NWC"2;
"S \NAC"
BN"10"27;
%"CAP"
"1","(-6250,1350)","2","mstr_discrete","I95";
;
LOCATION"C1M15"
PART_NUMBER"A36096-155"
VALUE"0.22UF"
TOLERANCE"10%"
PACK_TYPE"0402"
VOLTAGE"16V"
MATERIAL"X7R"
CDS_LIB"mstr_discrete"
BOM_COST"IO_SLOT"
CDS_SEC"1"
$SEC"1"
CDS_LOCATION"C1M15"
ROOM"PCIE_STEERING";
"A"
$PN"1"12;
"B"
$PN"2"10;
%"TAP"
"7","(-6250,1100)","0","mstr_standard","I96";
;
CDS_LIB"mstr_standard"
BODY_TYPE"PLUMBING"
HDL_TAP"TRUE";
"B \NAC \NWC"2;
"S \NAC"
BN"11"10;
%"TAP"
"3","(-6500,2900)","0","mstr_standard","I97";
;
CDS_LIB"mstr_standard"
BODY_TYPE"PLUMBING"
HDL_TAP"TRUE";
"B \NAC \NWC"3;
"S \NAC"
BN"12"24;
%"TAP"
"3","(-6700,2900)","0","mstr_standard","I98";
;
CDS_LIB"mstr_standard"
BODY_TYPE"PLUMBING"
HDL_TAP"TRUE";
"B \NAC \NWC"3;
"S \NAC"
BN"13"18;
%"TAP"
"3","(-6900,2900)","0","mstr_standard","I99";
;
CDS_LIB"mstr_standard"
BODY_TYPE"PLUMBING"
HDL_TAP"TRUE";
"B \NAC \NWC"3;
"S \NAC"
BN"14"20;
END.
